FILE_TYPE = CONNECTIVITY;
{Allegro Design Entry HDL 17.2-2016 S081 (4005846) 1/11/2022}
"PAGE_NUMBER" = 61;
0"NC";
1"GND\g";
2"GND\g";
3"SLOT2_SKU_ID0";
4"SLOT2_SKU_ID1";
5"P3V3_STBY\g";
6"SLOT2_BUF_SKU_ID0";
7"SLOT2_BUF_SKU_ID1";
8"PVDD18_S5_P1\g";
9"SLOT2_BUF_SKU_ID1";
10"SLOT2_BUF_SKU_ID0";
%"SN74LVC2G07DCKR"
"1","(-5000,2900)","0","pure_quanta","I17";
;
LOCATION"U24"
$SEC"1"
CDS_SEC"1"
MATERIAL"IC"
VALUE"SN74LVC2G07DCKR"
PART_NUMBER"AL002G07006"
PACK_TYPE"SMLF"
NEEDS_NO_SIZE"TRUE"
CDS_LIB"pure_quanta";
"VCC"
$PN"5"5;
"GND"
$PN"2"2;
"2Y"
$PN"4"7;
"1Y"
$PN"6"6;
"2A"
$PN"3"4;
"1A"
$PN"1"3;
%"UNIVERSAL_GND"
"1","(-4450,3000)","0","pure_quanta_power","I18";
;
CDS_LIB"pure_quanta_power"
HDL_POWER"GND";
"A"1;
%"UNIVERSAL_POWER"
"1","(-4525,3525)","2","pure_quanta_power","I19";
;
HDL_POWER"P3V3_STBY"
CDS_LIB"pure_quanta_power";
"A"5;
%"Q_CAP"
"1","(-4450,3200)","0","pure_quanta","I20";
;
LOCATION"C494"
$SEC"1"
CDS_SEC"1"
MATERIAL"X7R"
TOLERANCE"10%"
VALUE"0.1UF"
VOLTAGE"25V"
PACK_TYPE"0402"
CDS_LIB"pure_quanta"
PART_NUMBER"CH4104K1B00";
"B"
$PN"2"1;
"A"
$PN"1"5;
%"UNIVERSAL_GND"
"1","(-5425,2900)","5","pure_quanta_power","I25";
;
CDS_LIB"pure_quanta_power"
HDL_POWER"GND";
"A"2;
%"Q_RES"
"1","(-2525,3825)","0","pure_quanta","I26";
;
LOCATION"R652"
$SEC"1"
CDS_SEC"1"
VALUE"4.7K"
CDS_LIB"pure_quanta"
WATTAGE"1/16W"
MATERIAL"CHIP"
TOLERANCE"5%"
PART_NUMBER"TMP_QCS24702JB38"
PACK_TYPE"0402LF";
"B"
$PN"2"10;
"A"
$PN"1"8;
%"Q_RES"
"1","(-2525,3725)","0","pure_quanta","I27";
;
LOCATION"R653"
$SEC"1"
CDS_SEC"1"
VALUE"4.7K"
CDS_LIB"pure_quanta"
WATTAGE"1/16W"
MATERIAL"CHIP"
TOLERANCE"5%"
PART_NUMBER"TMP_QCS24702JB38"
PACK_TYPE"0402LF";
"B"
$PN"2"9;
"A"
$PN"1"8;
%"UNIVERSAL_POWER"
"1","(-2825,4100)","2","pure_quanta_power","I28";
;
HDL_POWER"PVDD18_S5_P1"
CDS_LIB"pure_quanta_power";
"A"8;
END.
